(kicad_pcb
	(version 20260206)
	(generator "pcbnew")
	(generator_version "10.0")
	(general
		(thickness 1.6)
		(legacy_teardrops no)
	)
	(paper "A4")
	(title_block
		(title "01162023_DA0F0TEBIF0_F0T_Expander_BD_F_brd_V02_OCP.brd")
		(comment 1 "Grand Teton / footprints 4187-4193 of 9728")
	)
	(layers
		(0 "F.Cu" signal "TOP")
		(4 "In1.Cu" signal "GND")
		(6 "In2.Cu" signal "VCC")
		(8 "In3.Cu" signal "VCC1")
		(10 "In4.Cu" signal "GND1")
		(12 "In5.Cu" signal "IN1")
		(14 "In6.Cu" signal "GND2")
		(16 "In7.Cu" signal "IN2")
		(18 "In8.Cu" signal "GND3")
		(20 "In9.Cu" signal "IN3")
		(22 "In10.Cu" signal "GND4")
		(24 "In11.Cu" signal "IN4")
		(26 "In12.Cu" signal "GND5")
		(28 "In13.Cu" signal "IN5")
		(30 "In14.Cu" signal "GND6")
		(32 "In15.Cu" signal "IN6")
		(34 "In16.Cu" signal "GND7")
		(2 "B.Cu" signal "BOTTOM")
		(9 "F.Adhes" user "F.Adhesive")
		(11 "B.Adhes" user "B.Adhesive")
		(13 "F.Paste" user "Package Geometry/Pastemask Top")
		(15 "B.Paste" user "Package Geometry/Pastemask Bottom")
		(5 "F.SilkS" user "Ref Des/Silkscreen Top")
		(7 "B.SilkS" user "Ref Des/Silkscreen Bottom")
		(1 "F.Mask" user "Board Geometry/Soldermask Top")
		(3 "B.Mask" user "Board Geometry/Soldermask Bottom")
		(17 "Dwgs.User" user "User.Drawings")
		(19 "Cmts.User" user "User.Comments")
		(21 "Eco1.User" user "User.Eco1")
		(23 "Eco2.User" user "User.Eco2")
		(25 "Edge.Cuts" user "Board Geometry/Outline")
		(27 "Margin" user)
		(31 "F.CrtYd" user "Package Geometry/Place Bound Top")
		(29 "B.CrtYd" user "Package Geometry/Place Bound Bottom")
		(35 "F.Fab" user "Ref Des/Assembly Top")
		(33 "B.Fab" user "Ref Des/Assembly Bottom")
	)
	(footprint ""
		(layer "F.Cu")
		(at 360.683556 -160.327848 180)
		(property "Reference" "PR7051"
			(at 0 0 180)
			(layer "F.SilkS")
			(hide yes)
			(effects
				(font
					(size 1.27 1.27)
				)
			)
		)
		(property "Value" ""
			(at 0 0 180)
			(layer "F.Fab")
			(effects
				(font
					(size 1.27 1.27)
				)
			)
		)
		(duplicate_pad_numbers_are_jumpers no)
		(fp_line
			(start 0.7874 0.4064)
			(end -0.7874 0.4064)
			(stroke
				(width 0.1524)
				(type default)
			)
			(layer "F.SilkS")
		)
		(fp_line
			(start 0.7874 -0.4064)
			(end 0.7874 0.4064)
			(stroke
				(width 0.1524)
				(type default)
			)
			(layer "F.SilkS")
		)
		(fp_line
			(start -0.7874 0.4064)
			(end -0.7874 -0.4064)
			(stroke
				(width 0.1524)
				(type default)
			)
			(layer "F.SilkS")
		)
		(fp_line
			(start -0.7874 -0.4064)
			(end 0.7874 -0.4064)
			(stroke
				(width 0.1524)
				(type default)
			)
			(layer "F.SilkS")
		)
		(fp_line
			(start 0.67945 0.3048)
			(end 0.120396 0.3048)
			(stroke
				(width 0.1)
				(type default)
			)
			(layer "F.Fab")
		)
		(fp_line
			(start 0.67945 -0.3048)
			(end 0.67945 0.3048)
			(stroke
				(width 0.1)
				(type default)
			)
			(layer "F.Fab")
		)
		(fp_line
			(start 0.12065 -0.2794)
			(end 0.12065 -0.3048)
			(stroke
				(width 0.1)
				(type default)
			)
			(layer "F.Fab")
		)
		(fp_line
			(start 0.12065 -0.3048)
			(end 0.67945 -0.3048)
			(stroke
				(width 0.1)
				(type default)
			)
			(layer "F.Fab")
		)
		(fp_line
			(start 0.120396 0.3048)
			(end 0.120396 0.2794)
			(stroke
				(width 0.1)
				(type default)
			)
			(layer "F.Fab")
		)
		(fp_line
			(start 0.120396 0.2794)
			(end -0.12065 0.2794)
			(stroke
				(width 0.1)
				(type default)
			)
			(layer "F.Fab")
		)
		(fp_line
			(start -0.12065 0.3048)
			(end -0.67945 0.3048)
			(stroke
				(width 0.1)
				(type default)
			)
			(layer "F.Fab")
		)
		(fp_line
			(start -0.12065 0.2794)
			(end -0.12065 0.3048)
			(stroke
				(width 0.1)
				(type default)
			)
			(layer "F.Fab")
		)
		(fp_line
			(start -0.12065 -0.2794)
			(end 0.12065 -0.2794)
			(stroke
				(width 0.1)
				(type default)
			)
			(layer "F.Fab")
		)
		(fp_line
			(start -0.12065 -0.305054)
			(end -0.12065 -0.2794)
			(stroke
				(width 0.1)
				(type default)
			)
			(layer "F.Fab")
		)
		(fp_line
			(start -0.67945 0.3048)
			(end -0.67945 -0.305054)
			(stroke
				(width 0.1)
				(type default)
			)
			(layer "F.Fab")
		)
		(fp_line
			(start -0.67945 -0.305054)
			(end -0.12065 -0.305054)
			(stroke
				(width 0.1)
				(type default)
			)
			(layer "F.Fab")
		)
		(pad "1" smd circle
			(at -0.40005 0 180)
			(size 0 0)
			(layers "F.Cu" "F.Mask" "F.Paste")
			(net "P12V_NIC6_CO_ISET")
		)
		(pad "2" smd circle
			(at 0.40005 0 180)
			(size 0 0)
			(layers "F.Cu" "F.Mask" "F.Paste")
			(net "P12V_NIC6_CO_ISET_R")
		)
	)
	(footprint ""
		(layer "F.Cu")
		(at 89.023444 -96.811592 -90)
		(property "Reference" "R694"
			(at 0 0 270)
			(layer "F.SilkS")
			(hide yes)
			(effects
				(font
					(size 1.27 1.27)
				)
			)
		)
		(property "Value" ""
			(at 0 0 270)
			(layer "F.Fab")
			(effects
				(font
					(size 1.27 1.27)
				)
			)
		)
		(duplicate_pad_numbers_are_jumpers no)
		(fp_line
			(start -0.7874 0.4064)
			(end -0.7874 -0.4064)
			(stroke
				(width 0.1524)
				(type default)
			)
			(layer "F.SilkS")
		)
		(fp_line
			(start 0.7874 0.4064)
			(end -0.7874 0.4064)
			(stroke
				(width 0.1524)
				(type default)
			)
			(layer "F.SilkS")
		)
		(fp_line
			(start -0.7874 -0.4064)
			(end 0.7874 -0.4064)
			(stroke
				(width 0.1524)
				(type default)
			)
			(layer "F.SilkS")
		)
		(fp_line
			(start 0.7874 -0.4064)
			(end 0.7874 0.4064)
			(stroke
				(width 0.1524)
				(type default)
			)
			(layer "F.SilkS")
		)
		(fp_line
			(start -0.67945 0.3048)
			(end -0.67945 -0.305054)
			(stroke
				(width 0.1)
				(type default)
			)
			(layer "F.Fab")
		)
		(fp_line
			(start -0.12065 0.3048)
			(end -0.67945 0.3048)
			(stroke
				(width 0.1)
				(type default)
			)
			(layer "F.Fab")
		)
		(fp_line
			(start 0.120396 0.3048)
			(end 0.120396 0.2794)
			(stroke
				(width 0.1)
				(type default)
			)
			(layer "F.Fab")
		)
		(fp_line
			(start 0.67945 0.3048)
			(end 0.120396 0.3048)
			(stroke
				(width 0.1)
				(type default)
			)
			(layer "F.Fab")
		)
		(fp_line
			(start -0.12065 0.2794)
			(end -0.12065 0.3048)
			(stroke
				(width 0.1)
				(type default)
			)
			(layer "F.Fab")
		)
		(fp_line
			(start 0.120396 0.2794)
			(end -0.12065 0.2794)
			(stroke
				(width 0.1)
				(type default)
			)
			(layer "F.Fab")
		)
		(fp_line
			(start -0.12065 -0.2794)
			(end 0.12065 -0.2794)
			(stroke
				(width 0.1)
				(type default)
			)
			(layer "F.Fab")
		)
		(fp_line
			(start 0.12065 -0.2794)
			(end 0.12065 -0.3048)
			(stroke
				(width 0.1)
				(type default)
			)
			(layer "F.Fab")
		)
		(fp_line
			(start 0.12065 -0.3048)
			(end 0.67945 -0.3048)
			(stroke
				(width 0.1)
				(type default)
			)
			(layer "F.Fab")
		)
		(fp_line
			(start 0.67945 -0.3048)
			(end 0.67945 0.3048)
			(stroke
				(width 0.1)
				(type default)
			)
			(layer "F.Fab")
		)
		(fp_line
			(start -0.67945 -0.305054)
			(end -0.12065 -0.305054)
			(stroke
				(width 0.1)
				(type default)
			)
			(layer "F.Fab")
		)
		(fp_line
			(start -0.12065 -0.305054)
			(end -0.12065 -0.2794)
			(stroke
				(width 0.1)
				(type default)
			)
			(layer "F.Fab")
		)
		(pad "1" smd circle
			(at -0.40005 0 270)
			(size 0 0)
			(layers "F.Cu" "F.Mask" "F.Paste")
			(net "NIC1_ADC_A0")
		)
		(pad "2" smd circle
			(at 0.40005 0 270)
			(size 0 0)
			(layers "F.Cu" "F.Mask" "F.Paste")
			(net "P3V3_AUX")
		)
	)
	(footprint ""
		(layer "F.Cu")
		(at 213.990936 -188.652404 90)
		(property "Reference" "R5302"
			(at 0 0 90)
			(layer "F.SilkS")
			(hide yes)
			(effects
				(font
					(size 1.27 1.27)
				)
			)
		)
		(property "Value" ""
			(at 0 0 90)
			(layer "F.Fab")
			(effects
				(font
					(size 1.27 1.27)
				)
			)
		)
		(duplicate_pad_numbers_are_jumpers no)
		(fp_line
			(start 0.7874 -0.4064)
			(end 0.7874 0.4064)
			(stroke
				(width 0.1524)
				(type default)
			)
			(layer "F.SilkS")
		)
		(fp_line
			(start -0.7874 -0.4064)
			(end 0.7874 -0.4064)
			(stroke
				(width 0.1524)
				(type default)
			)
			(layer "F.SilkS")
		)
		(fp_line
			(start 0.7874 0.4064)
			(end -0.7874 0.4064)
			(stroke
				(width 0.1524)
				(type default)
			)
			(layer "F.SilkS")
		)
		(fp_line
			(start -0.7874 0.4064)
			(end -0.7874 -0.4064)
			(stroke
				(width 0.1524)
				(type default)
			)
			(layer "F.SilkS")
		)
		(fp_line
			(start -0.12065 -0.305054)
			(end -0.12065 -0.2794)
			(stroke
				(width 0.1)
				(type default)
			)
			(layer "F.Fab")
		)
		(fp_line
			(start -0.67945 -0.305054)
			(end -0.12065 -0.305054)
			(stroke
				(width 0.1)
				(type default)
			)
			(layer "F.Fab")
		)
		(fp_line
			(start 0.67945 -0.3048)
			(end 0.67945 0.3048)
			(stroke
				(width 0.1)
				(type default)
			)
			(layer "F.Fab")
		)
		(fp_line
			(start 0.12065 -0.3048)
			(end 0.67945 -0.3048)
			(stroke
				(width 0.1)
				(type default)
			)
			(layer "F.Fab")
		)
		(fp_line
			(start 0.12065 -0.2794)
			(end 0.12065 -0.3048)
			(stroke
				(width 0.1)
				(type default)
			)
			(layer "F.Fab")
		)
		(fp_line
			(start -0.12065 -0.2794)
			(end 0.12065 -0.2794)
			(stroke
				(width 0.1)
				(type default)
			)
			(layer "F.Fab")
		)
		(fp_line
			(start 0.120396 0.2794)
			(end -0.12065 0.2794)
			(stroke
				(width 0.1)
				(type default)
			)
			(layer "F.Fab")
		)
		(fp_line
			(start -0.12065 0.2794)
			(end -0.12065 0.3048)
			(stroke
				(width 0.1)
				(type default)
			)
			(layer "F.Fab")
		)
		(fp_line
			(start 0.67945 0.3048)
			(end 0.120396 0.3048)
			(stroke
				(width 0.1)
				(type default)
			)
			(layer "F.Fab")
		)
		(fp_line
			(start 0.120396 0.3048)
			(end 0.120396 0.2794)
			(stroke
				(width 0.1)
				(type default)
			)
			(layer "F.Fab")
		)
		(fp_line
			(start -0.12065 0.3048)
			(end -0.67945 0.3048)
			(stroke
				(width 0.1)
				(type default)
			)
			(layer "F.Fab")
		)
		(fp_line
			(start -0.67945 0.3048)
			(end -0.67945 -0.305054)
			(stroke
				(width 0.1)
				(type default)
			)
			(layer "F.Fab")
		)
		(pad "1" smd circle
			(at -0.40005 0 90)
			(size 0 0)
			(layers "F.Cu" "F.Mask" "F.Paste")
			(net "BIC_SEL_FLASH_SW1_R")
		)
		(pad "2" smd circle
			(at 0.40005 0 90)
			(size 0 0)
			(layers "F.Cu" "F.Mask" "F.Paste")
			(net "P3V3_AUX")
		)
	)
	(footprint ""
		(layer "F.Cu")
		(at 78.267052 -57.332626)
		(property "Reference" "R6839"
			(at 0 0 0)
			(layer "F.SilkS")
			(hide yes)
			(effects
				(font
					(size 1.27 1.27)
				)
			)
		)
		(property "Value" ""
			(at 0 0 0)
			(layer "F.Fab")
			(effects
				(font
					(size 1.27 1.27)
				)
			)
		)
		(duplicate_pad_numbers_are_jumpers no)
		(fp_line
			(start -0.7874 -0.4064)
			(end 0.7874 -0.4064)
			(stroke
				(width 0.1524)
				(type default)
			)
			(layer "F.SilkS")
		)
		(fp_line
			(start -0.7874 0.4064)
			(end -0.7874 -0.4064)
			(stroke
				(width 0.1524)
				(type default)
			)
			(layer "F.SilkS")
		)
		(fp_line
			(start 0.7874 -0.4064)
			(end 0.7874 0.4064)
			(stroke
				(width 0.1524)
				(type default)
			)
			(layer "F.SilkS")
		)
		(fp_line
			(start 0.7874 0.4064)
			(end -0.7874 0.4064)
			(stroke
				(width 0.1524)
				(type default)
			)
			(layer "F.SilkS")
		)
		(fp_line
			(start -0.67945 -0.305054)
			(end -0.12065 -0.305054)
			(stroke
				(width 0.1)
				(type default)
			)
			(layer "F.Fab")
		)
		(fp_line
			(start -0.67945 0.3048)
			(end -0.67945 -0.305054)
			(stroke
				(width 0.1)
				(type default)
			)
			(layer "F.Fab")
		)
		(fp_line
			(start -0.12065 -0.305054)
			(end -0.12065 -0.2794)
			(stroke
				(width 0.1)
				(type default)
			)
			(layer "F.Fab")
		)
		(fp_line
			(start -0.12065 -0.2794)
			(end 0.12065 -0.2794)
			(stroke
				(width 0.1)
				(type default)
			)
			(layer "F.Fab")
		)
		(fp_line
			(start -0.12065 0.2794)
			(end -0.12065 0.3048)
			(stroke
				(width 0.1)
				(type default)
			)
			(layer "F.Fab")
		)
		(fp_line
			(start -0.12065 0.3048)
			(end -0.67945 0.3048)
			(stroke
				(width 0.1)
				(type default)
			)
			(layer "F.Fab")
		)
		(fp_line
			(start 0.120396 0.2794)
			(end -0.12065 0.2794)
			(stroke
				(width 0.1)
				(type default)
			)
			(layer "F.Fab")
		)
		(fp_line
			(start 0.120396 0.3048)
			(end 0.120396 0.2794)
			(stroke
				(width 0.1)
				(type default)
			)
			(layer "F.Fab")
		)
		(fp_line
			(start 0.12065 -0.3048)
			(end 0.67945 -0.3048)
			(stroke
				(width 0.1)
				(type default)
			)
			(layer "F.Fab")
		)
		(fp_line
			(start 0.12065 -0.2794)
			(end 0.12065 -0.3048)
			(stroke
				(width 0.1)
				(type default)
			)
			(layer "F.Fab")
		)
		(fp_line
			(start 0.67945 -0.3048)
			(end 0.67945 0.3048)
			(stroke
				(width 0.1)
				(type default)
			)
			(layer "F.Fab")
		)
		(fp_line
			(start 0.67945 0.3048)
			(end 0.120396 0.3048)
			(stroke
				(width 0.1)
				(type default)
			)
			(layer "F.Fab")
		)
		(pad "1" smd circle
			(at -0.40005 0)
			(size 0 0)
			(layers "F.Cu" "F.Mask" "F.Paste")
			(net "SSD2_PWR_EN_R")
		)
		(pad "2" smd circle
			(at 0.40005 0)
			(size 0 0)
			(layers "F.Cu" "F.Mask" "F.Paste")
			(net "GND")
		)
	)
	(footprint ""
		(layer "F.Cu")
		(at 295.767252 -171.675806)
		(property "Reference" "R253"
			(at 0 0 0)
			(layer "F.SilkS")
			(hide yes)
			(effects
				(font
					(size 1.27 1.27)
				)
			)
		)
		(property "Value" ""
			(at 0 0 0)
			(layer "F.Fab")
			(effects
				(font
					(size 1.27 1.27)
				)
			)
		)
		(duplicate_pad_numbers_are_jumpers no)
		(fp_line
			(start -0.7874 -0.4064)
			(end 0.7874 -0.4064)
			(stroke
				(width 0.1524)
				(type default)
			)
			(layer "F.SilkS")
		)
		(fp_line
			(start -0.7874 0.4064)
			(end -0.7874 -0.4064)
			(stroke
				(width 0.1524)
				(type default)
			)
			(layer "F.SilkS")
		)
		(fp_line
			(start 0.7874 -0.4064)
			(end 0.7874 0.4064)
			(stroke
				(width 0.1524)
				(type default)
			)
			(layer "F.SilkS")
		)
		(fp_line
			(start 0.7874 0.4064)
			(end -0.7874 0.4064)
			(stroke
				(width 0.1524)
				(type default)
			)
			(layer "F.SilkS")
		)
		(fp_line
			(start -0.67945 -0.305054)
			(end -0.12065 -0.305054)
			(stroke
				(width 0.1)
				(type default)
			)
			(layer "F.Fab")
		)
		(fp_line
			(start -0.67945 0.3048)
			(end -0.67945 -0.305054)
			(stroke
				(width 0.1)
				(type default)
			)
			(layer "F.Fab")
		)
		(fp_line
			(start -0.12065 -0.305054)
			(end -0.12065 -0.2794)
			(stroke
				(width 0.1)
				(type default)
			)
			(layer "F.Fab")
		)
		(fp_line
			(start -0.12065 -0.2794)
			(end 0.12065 -0.2794)
			(stroke
				(width 0.1)
				(type default)
			)
			(layer "F.Fab")
		)
		(fp_line
			(start -0.12065 0.2794)
			(end -0.12065 0.3048)
			(stroke
				(width 0.1)
				(type default)
			)
			(layer "F.Fab")
		)
		(fp_line
			(start -0.12065 0.3048)
			(end -0.67945 0.3048)
			(stroke
				(width 0.1)
				(type default)
			)
			(layer "F.Fab")
		)
		(fp_line
			(start 0.120396 0.2794)
			(end -0.12065 0.2794)
			(stroke
				(width 0.1)
				(type default)
			)
			(layer "F.Fab")
		)
		(fp_line
			(start 0.120396 0.3048)
			(end 0.120396 0.2794)
			(stroke
				(width 0.1)
				(type default)
			)
			(layer "F.Fab")
		)
		(fp_line
			(start 0.12065 -0.3048)
			(end 0.67945 -0.3048)
			(stroke
				(width 0.1)
				(type default)
			)
			(layer "F.Fab")
		)
		(fp_line
			(start 0.12065 -0.2794)
			(end 0.12065 -0.3048)
			(stroke
				(width 0.1)
				(type default)
			)
			(layer "F.Fab")
		)
		(fp_line
			(start 0.67945 -0.3048)
			(end 0.67945 0.3048)
			(stroke
				(width 0.1)
				(type default)
			)
			(layer "F.Fab")
		)
		(fp_line
			(start 0.67945 0.3048)
			(end 0.120396 0.3048)
			(stroke
				(width 0.1)
				(type default)
			)
			(layer "F.Fab")
		)
		(pad "1" smd circle
			(at -0.40005 0)
			(size 0 0)
			(layers "F.Cu" "F.Mask" "F.Paste")
			(net "P3V3_NIC4")
		)
		(pad "2" smd circle
			(at 0.40005 0)
			(size 0 0)
			(layers "F.Cu" "F.Mask" "F.Paste")
			(net "HP_NIC4_PWRGD")
		)
	)
	(footprint ""
		(layer "F.Cu")
		(at 216.920572 -70.307454 90)
		(property "Reference" "PC849"
			(at 0 0 90)
			(layer "F.SilkS")
			(hide yes)
			(effects
				(font
					(size 1.27 1.27)
				)
			)
		)
		(property "Value" ""
			(at 0 0 90)
			(layer "F.Fab")
			(effects
				(font
					(size 1.27 1.27)
				)
			)
		)
		(duplicate_pad_numbers_are_jumpers no)
		(fp_line
			(start 0.7874 -0.4064)
			(end 0.7874 0.4064)
			(stroke
				(width 0.1524)
				(type default)
			)
			(layer "F.SilkS")
		)
		(fp_line
			(start -0.7874 -0.4064)
			(end 0.7874 -0.4064)
			(stroke
				(width 0.1524)
				(type default)
			)
			(layer "F.SilkS")
		)
		(fp_line
			(start 0.7874 0.4064)
			(end -0.7874 0.4064)
			(stroke
				(width 0.1524)
				(type default)
			)
			(layer "F.SilkS")
		)
		(fp_line
			(start -0.7874 0.4064)
			(end -0.7874 -0.4064)
			(stroke
				(width 0.1524)
				(type default)
			)
			(layer "F.SilkS")
		)
		(fp_line
			(start -0.12065 -0.305054)
			(end -0.12065 -0.2794)
			(stroke
				(width 0.1)
				(type default)
			)
			(layer "F.Fab")
		)
		(fp_line
			(start -0.67945 -0.305054)
			(end -0.12065 -0.305054)
			(stroke
				(width 0.1)
				(type default)
			)
			(layer "F.Fab")
		)
		(fp_line
			(start 0.67945 -0.3048)
			(end 0.67945 0.3048)
			(stroke
				(width 0.1)
				(type default)
			)
			(layer "F.Fab")
		)
		(fp_line
			(start 0.12065 -0.3048)
			(end 0.67945 -0.3048)
			(stroke
				(width 0.1)
				(type default)
			)
			(layer "F.Fab")
		)
		(fp_line
			(start 0.12065 -0.2794)
			(end 0.12065 -0.3048)
			(stroke
				(width 0.1)
				(type default)
			)
			(layer "F.Fab")
		)
		(fp_line
			(start -0.12065 -0.2794)
			(end 0.12065 -0.2794)
			(stroke
				(width 0.1)
				(type default)
			)
			(layer "F.Fab")
		)
		(fp_line
			(start 0.120396 0.2794)
			(end -0.12065 0.2794)
			(stroke
				(width 0.1)
				(type default)
			)
			(layer "F.Fab")
		)
		(fp_line
			(start -0.12065 0.2794)
			(end -0.12065 0.3048)
			(stroke
				(width 0.1)
				(type default)
			)
			(layer "F.Fab")
		)
		(fp_line
			(start 0.67945 0.3048)
			(end 0.120396 0.3048)
			(stroke
				(width 0.1)
				(type default)
			)
			(layer "F.Fab")
		)
		(fp_line
			(start 0.120396 0.3048)
			(end 0.120396 0.2794)
			(stroke
				(width 0.1)
				(type default)
			)
			(layer "F.Fab")
		)
		(fp_line
			(start -0.12065 0.3048)
			(end -0.67945 0.3048)
			(stroke
				(width 0.1)
				(type default)
			)
			(layer "F.Fab")
		)
		(fp_line
			(start -0.67945 0.3048)
			(end -0.67945 -0.305054)
			(stroke
				(width 0.1)
				(type default)
			)
			(layer "F.Fab")
		)
		(pad "1" smd circle
			(at -0.40005 0 90)
			(size 0 0)
			(layers "F.Cu" "F.Mask" "F.Paste")
			(net "P12V_AUX")
		)
		(pad "2" smd circle
			(at 0.40005 0 90)
			(size 0 0)
			(layers "F.Cu" "F.Mask" "F.Paste")
			(net "GND")
		)
	)
	(footprint ""
		(layer "F.Cu")
		(at 387.580632 -111.003334)
		(property "Reference" "C685"
			(at 0 0 0)
			(layer "F.SilkS")
			(hide yes)
			(effects
				(font
					(size 1.27 1.27)
				)
			)
		)
		(property "Value" ""
			(at 0 0 0)
			(layer "F.Fab")
			(effects
				(font
					(size 1.27 1.27)
				)
			)
		)
		(duplicate_pad_numbers_are_jumpers no)
		(fp_line
			(start -0.299974 -0.150114)
			(end 0.299974 -0.150114)
			(stroke
				(width 0.1)
				(type default)
			)
			(layer "F.Fab")
		)
		(fp_line
			(start -0.299974 0.150114)
			(end -0.299974 -0.150114)
			(stroke
				(width 0.1)
				(type default)
			)
			(layer "F.Fab")
		)
		(fp_line
			(start 0.299974 -0.150114)
			(end 0.299974 0.150114)
			(stroke
				(width 0.1)
				(type default)
			)
			(layer "F.Fab")
		)
		(fp_line
			(start 0.299974 0.150114)
			(end -0.299974 0.150114)
			(stroke
				(width 0.1)
				(type default)
			)
			(layer "F.Fab")
		)
		(pad "1" smd rect
			(at -0.2667 0)
			(size 0.3048 0.381)
			(layers "F.Cu" "F.Mask" "F.Paste")
			(net "P5E_PEX3_STN1_TX_DN<22>")
		)
		(pad "2" smd rect
			(at 0.2667 0)
			(size 0.3048 0.381)
			(layers "F.Cu" "F.Mask" "F.Paste")
			(net "P5E_PEX3_STN1_TX_C_DN<22>")
		)
	)
)
